(kicad_pcb
	(version 20260206)
	(generator "pcbnew")
	(generator_version "10.0")
	(general
		(thickness 1.6)
		(legacy_teardrops no)
	)
	(paper "A4")
	(title_block
		(title "Bryce Canyon_F.DPB_16315-1-OCP.brd")
		(comment 1 "Bryce Canyon / footprints 1989-1994 of 2223")
	)
	(layers
		(0 "F.Cu" signal "TOP")
		(4 "In1.Cu" signal "L2GND")
		(6 "In2.Cu" signal "L3")
		(8 "In3.Cu" signal "L4GND")
		(10 "In4.Cu" signal "L5")
		(12 "In5.Cu" signal "L6VCC")
		(14 "In6.Cu" signal "L7VCC")
		(16 "In7.Cu" signal "L8")
		(18 "In8.Cu" signal "L9GND")
		(20 "In9.Cu" signal "L10")
		(22 "In10.Cu" signal "L11GND")
		(2 "B.Cu" signal "BOTTOM")
		(9 "F.Adhes" user "F.Adhesive")
		(11 "B.Adhes" user "B.Adhesive")
		(13 "F.Paste" user "Package Geometry/Pastemask Top")
		(15 "B.Paste" user "Package Geometry/Pastemask Bottom")
		(5 "F.SilkS" user "Ref Des/Silkscreen Top")
		(7 "B.SilkS" user "Ref Des/Silkscreen Bottom")
		(1 "F.Mask" user "Board Geometry/Soldermask Top")
		(3 "B.Mask" user "Board Geometry/Soldermask Bottom")
		(17 "Dwgs.User" user "User.Drawings")
		(19 "Cmts.User" user "User.Comments")
		(21 "Eco1.User" user "User.Eco1")
		(23 "Eco2.User" user "User.Eco2")
		(25 "Edge.Cuts" user "Board Geometry/Outline")
		(27 "Margin" user)
		(31 "F.CrtYd" user "Package Geometry/Place Bound Top")
		(29 "B.CrtYd" user "Package Geometry/Place Bound Bottom")
		(35 "F.Fab" user "Ref Des/Assembly Top")
		(33 "B.Fab" user "Ref Des/Assembly Bottom")
	)
	(footprint ""
		(layer "F.Cu")
		(at 276.2377 15.3162 90)
		(property "Reference" "R632"
			(at 0 0 90)
			(layer "F.SilkS")
			(hide yes)
			(effects
				(font
					(size 1.27 1.27)
				)
			)
		)
		(property "Value" "10KR2F-2-GP"
			(at 0.064008 -3.993896 90)
			(unlocked yes)
			(layer "F.Fab")
			(hide yes)
			(effects
				(font
					(size 1.016 1.016)
					(thickness 0.1524)
				)
			)
		)
		(property "Device Type" "R402H16"
			(at 0.064008 -5.517896 90)
			(unlocked yes)
			(layer "F.Fab")
			(hide yes)
			(effects
				(font
					(size 1.016 1.016)
					(thickness 0.1524)
				)
			)
		)
		(duplicate_pad_numbers_are_jumpers no)
		(fp_line
			(start 0.508 -0.9398)
			(end -0.508 -0.9398)
			(stroke
				(width 0.1524)
				(type default)
			)
			(layer "F.SilkS")
		)
		(fp_line
			(start -0.508 -0.9398)
			(end -0.508 0.9398)
			(stroke
				(width 0.1524)
				(type default)
			)
			(layer "F.SilkS")
		)
		(fp_rect
			(start -0.508 0.9398)
			(end 0.508 -0.9398)
			(stroke
				(width 0)
				(type default)
			)
			(fill no)
			(layer "F.CrtYd")
		)
		(fp_rect
			(start -0.508 0.9398)
			(end 0.508 -0.9398)
			(stroke
				(width 0)
				(type default)
			)
			(fill no)
			(layer "F.Fab")
		)
		(pad "1" smd custom
			(at 0 -0.4445 90)
			(size 0.1397 0.1397)
			(layers "F.Cu" "F.Mask" "F.Paste")
			(net "P3V3_STBY_B")
			(options
				(clearance outline)
				(anchor circle)
			)
			(primitives
				(gr_poly
					(pts
						(arc
							(start -0.1778 -0.2794)
							(mid -0.249642 -0.249642)
							(end -0.2794 -0.1778)
						)
						(arc
							(start -0.2794 0.1778)
							(mid -0.249642 0.249642)
							(end -0.1778 0.2794)
						)
						(arc
							(start 0.1778 0.2794)
							(mid 0.249642 0.249642)
							(end 0.2794 0.1778)
						)
						(arc
							(start 0.2794 -0.1778)
							(mid 0.249642 -0.249642)
							(end 0.1778 -0.2794)
						)
					)
					(width 0)
					(fill yes)
				)
			)
		)
		(pad "2" smd custom
			(at 0 0.4445 90)
			(size 0.1397 0.1397)
			(layers "F.Cu" "F.Mask" "F.Paste")
			(net "IOM_B_PWR_LED")
			(options
				(clearance outline)
				(anchor circle)
			)
			(primitives
				(gr_poly
					(pts
						(arc
							(start -0.1778 -0.2794)
							(mid -0.249642 -0.249642)
							(end -0.2794 -0.1778)
						)
						(arc
							(start -0.2794 0.1778)
							(mid -0.249642 0.249642)
							(end -0.1778 0.2794)
						)
						(arc
							(start 0.1778 0.2794)
							(mid 0.249642 0.249642)
							(end 0.2794 0.1778)
						)
						(arc
							(start 0.2794 -0.1778)
							(mid 0.249642 -0.249642)
							(end 0.1778 -0.2794)
						)
					)
					(width 0)
					(fill yes)
				)
			)
		)
	)
	(footprint ""
		(layer "F.Cu")
		(at 77.892148 -45.633894 90)
		(property "Reference" "R742"
			(at 0 0 90)
			(layer "F.SilkS")
			(hide yes)
			(effects
				(font
					(size 1.27 1.27)
				)
			)
		)
		(property "Value" "4K7R2J-2-GP"
			(at 0.064008 -3.993896 90)
			(unlocked yes)
			(layer "F.Fab")
			(hide yes)
			(effects
				(font
					(size 1.016 1.016)
					(thickness 0.1524)
				)
			)
		)
		(property "Device Type" "R402H16"
			(at 0.064008 -5.517896 90)
			(unlocked yes)
			(layer "F.Fab")
			(hide yes)
			(effects
				(font
					(size 1.016 1.016)
					(thickness 0.1524)
				)
			)
		)
		(duplicate_pad_numbers_are_jumpers no)
		(fp_line
			(start 0.508 -0.9398)
			(end -0.508 -0.9398)
			(stroke
				(width 0.1524)
				(type default)
			)
			(layer "F.SilkS")
		)
		(fp_line
			(start -0.508 -0.9398)
			(end -0.508 0.9398)
			(stroke
				(width 0.1524)
				(type default)
			)
			(layer "F.SilkS")
		)
		(fp_rect
			(start -0.508 0.9398)
			(end 0.508 -0.9398)
			(stroke
				(width 0)
				(type default)
			)
			(fill no)
			(layer "F.CrtYd")
		)
		(fp_rect
			(start -0.508 0.9398)
			(end 0.508 -0.9398)
			(stroke
				(width 0)
				(type default)
			)
			(fill no)
			(layer "F.Fab")
		)
		(pad "1" smd custom
			(at 0 -0.4445 90)
			(size 0.1397 0.1397)
			(layers "F.Cu" "F.Mask" "F.Paste")
			(net "P12V_A")
			(options
				(clearance outline)
				(anchor circle)
			)
			(primitives
				(gr_poly
					(pts
						(arc
							(start -0.1778 -0.2794)
							(mid -0.249642 -0.249642)
							(end -0.2794 -0.1778)
						)
						(arc
							(start -0.2794 0.1778)
							(mid -0.249642 0.249642)
							(end -0.1778 0.2794)
						)
						(arc
							(start 0.1778 0.2794)
							(mid 0.249642 0.249642)
							(end 0.2794 0.1778)
						)
						(arc
							(start 0.2794 -0.1778)
							(mid 0.249642 -0.249642)
							(end 0.1778 -0.2794)
						)
					)
					(width 0)
					(fill yes)
				)
			)
		)
		(pad "2" smd custom
			(at 0 0.4445 90)
			(size 0.1397 0.1397)
			(layers "F.Cu" "F.Mask" "F.Paste")
			(net "SW_HDD_R26")
			(options
				(clearance outline)
				(anchor circle)
			)
			(primitives
				(gr_poly
					(pts
						(arc
							(start -0.1778 -0.2794)
							(mid -0.249642 -0.249642)
							(end -0.2794 -0.1778)
						)
						(arc
							(start -0.2794 0.1778)
							(mid -0.249642 0.249642)
							(end -0.1778 0.2794)
						)
						(arc
							(start 0.1778 0.2794)
							(mid 0.249642 0.249642)
							(end 0.2794 0.1778)
						)
						(arc
							(start 0.2794 -0.1778)
							(mid 0.249642 -0.249642)
							(end 0.1778 -0.2794)
						)
					)
					(width 0)
					(fill yes)
				)
			)
		)
	)
	(footprint ""
		(layer "F.Cu")
		(at 271.4498 -280.3144)
		(property "Reference" "C36"
			(at 0 0 0)
			(layer "F.SilkS")
			(hide yes)
			(effects
				(font
					(size 1.27 1.27)
				)
			)
		)
		(property "Value" "SCD1U16V2KX-3GP"
			(at 1.1811 -2.7051 0)
			(unlocked yes)
			(layer "F.Fab")
			(hide yes)
			(effects
				(font
					(size 1.016 1.016)
					(thickness 0.1524)
				)
			)
		)
		(property "Device Type" "C402H22"
			(at 1.1811 -4.2291 0)
			(unlocked yes)
			(layer "F.Fab")
			(hide yes)
			(effects
				(font
					(size 1.016 1.016)
					(thickness 0.1524)
				)
			)
		)
		(duplicate_pad_numbers_are_jumpers no)
		(fp_rect
			(start -0.4318 0.9525)
			(end 0.4318 -0.9525)
			(stroke
				(width 0)
				(type default)
			)
			(fill no)
			(layer "F.CrtYd")
		)
		(fp_rect
			(start -0.4318 0.9525)
			(end 0.4318 -0.9525)
			(stroke
				(width 0)
				(type default)
			)
			(fill no)
			(layer "F.Fab")
		)
		(pad "1" smd custom
			(at 0 -0.4445)
			(size 0.1524 0.1524)
			(layers "F.Cu" "F.Mask" "F.Paste")
			(net "P3V3_STBY_A")
			(options
				(clearance outline)
				(anchor circle)
			)
			(primitives
				(gr_poly
					(pts
						(arc
							(start 0.3048 -0.2032)
							(mid 0.275042 -0.275042)
							(end 0.2032 -0.3048)
						)
						(arc
							(start -0.2032 -0.3048)
							(mid -0.275042 -0.275042)
							(end -0.3048 -0.2032)
						)
						(arc
							(start -0.3048 0.2032)
							(mid -0.275042 0.275042)
							(end -0.2032 0.3048)
						)
						(arc
							(start 0.2032 0.3048)
							(mid 0.275042 0.275042)
							(end 0.3048 0.2032)
						)
					)
					(width 0)
					(fill yes)
				)
			)
		)
		(pad "2" smd custom
			(at 0 0.4445)
			(size 0.1524 0.1524)
			(layers "F.Cu" "F.Mask" "F.Paste")
			(net "GND")
			(options
				(clearance outline)
				(anchor circle)
			)
			(primitives
				(gr_poly
					(pts
						(arc
							(start 0.3048 -0.2032)
							(mid 0.275042 -0.275042)
							(end 0.2032 -0.3048)
						)
						(arc
							(start -0.2032 -0.3048)
							(mid -0.275042 -0.275042)
							(end -0.3048 -0.2032)
						)
						(arc
							(start -0.3048 0.2032)
							(mid -0.275042 0.275042)
							(end -0.2032 0.3048)
						)
						(arc
							(start 0.2032 0.3048)
							(mid 0.275042 0.275042)
							(end 0.3048 0.2032)
						)
					)
					(width 0)
					(fill yes)
				)
			)
		)
	)
	(footprint ""
		(layer "F.Cu")
		(at 392.91895 -181.842918 180)
		(property "Reference" "C300"
			(at 0 0 180)
			(layer "F.SilkS")
			(hide yes)
			(effects
				(font
					(size 1.27 1.27)
				)
			)
		)
		(property "Value" "SC1U16V3KX-5GP"
			(at 0 -2.8194 180)
			(unlocked yes)
			(layer "F.Fab")
			(hide yes)
			(effects
				(font
					(size 1.016 1.016)
					(thickness 0.1524)
				)
			)
		)
		(property "Device Type" "C603H36"
			(at 0 -4.3434 180)
			(unlocked yes)
			(layer "F.Fab")
			(hide yes)
			(effects
				(font
					(size 1.016 1.016)
					(thickness 0.1524)
				)
			)
		)
		(duplicate_pad_numbers_are_jumpers no)
		(fp_line
			(start 0.508 0)
			(end -0.508 0)
			(stroke
				(width 0.2032)
				(type default)
			)
			(layer "F.SilkS")
		)
		(fp_rect
			(start -0.5842 1.3335)
			(end 0.5842 -1.3335)
			(stroke
				(width 0)
				(type default)
			)
			(fill no)
			(layer "F.CrtYd")
		)
		(fp_rect
			(start -0.5842 1.3335)
			(end 0.5842 -1.3335)
			(stroke
				(width 0)
				(type default)
			)
			(fill no)
			(layer "F.Fab")
		)
		(pad "1" smd custom
			(at 0 -0.762 180)
			(size 0.2159 0.2159)
			(layers "F.Cu" "F.Mask" "F.Paste")
			(net "P5V_HDD20")
			(options
				(clearance outline)
				(anchor circle)
			)
			(primitives
				(gr_poly
					(pts
						(arc
							(start -0.3302 -0.4318)
							(mid -0.402042 -0.402042)
							(end -0.4318 -0.3302)
						)
						(arc
							(start -0.4318 0.3302)
							(mid -0.402042 0.402042)
							(end -0.3302 0.4318)
						)
						(arc
							(start 0.3302 0.4318)
							(mid 0.402042 0.402042)
							(end 0.4318 0.3302)
						)
						(arc
							(start 0.4318 -0.3302)
							(mid 0.402042 -0.402042)
							(end 0.3302 -0.4318)
						)
					)
					(width 0)
					(fill yes)
				)
			)
		)
		(pad "2" smd custom
			(at 0 0.762 180)
			(size 0.2159 0.2159)
			(layers "F.Cu" "F.Mask" "F.Paste")
			(net "GND")
			(options
				(clearance outline)
				(anchor circle)
			)
			(primitives
				(gr_poly
					(pts
						(arc
							(start -0.3302 -0.4318)
							(mid -0.402042 -0.402042)
							(end -0.4318 -0.3302)
						)
						(arc
							(start -0.4318 0.3302)
							(mid -0.402042 0.402042)
							(end -0.3302 0.4318)
						)
						(arc
							(start 0.3302 0.4318)
							(mid 0.402042 0.402042)
							(end 0.4318 0.3302)
						)
						(arc
							(start 0.4318 -0.3302)
							(mid 0.402042 -0.402042)
							(end 0.3302 -0.4318)
						)
					)
					(width 0)
					(fill yes)
				)
			)
		)
	)
	(footprint ""
		(layer "F.Cu")
		(at 113.150396 -160.633918)
		(property "Reference" "R492"
			(at 0 0 0)
			(layer "F.SilkS")
			(hide yes)
			(effects
				(font
					(size 1.27 1.27)
				)
			)
		)
		(property "Value" "0R2J-2-GP"
			(at 0.064008 -3.993896 0)
			(unlocked yes)
			(layer "F.Fab")
			(hide yes)
			(effects
				(font
					(size 1.016 1.016)
					(thickness 0.1524)
				)
			)
		)
		(property "Device Type" "R402H16"
			(at 0.064008 -5.517896 0)
			(unlocked yes)
			(layer "F.Fab")
			(hide yes)
			(effects
				(font
					(size 1.016 1.016)
					(thickness 0.1524)
				)
			)
		)
		(duplicate_pad_numbers_are_jumpers no)
		(fp_line
			(start -0.508 -0.9398)
			(end -0.508 0.9398)
			(stroke
				(width 0.1524)
				(type default)
			)
			(layer "F.SilkS")
		)
		(fp_line
			(start 0.508 -0.9398)
			(end -0.508 -0.9398)
			(stroke
				(width 0.1524)
				(type default)
			)
			(layer "F.SilkS")
		)
		(fp_rect
			(start -0.508 0.9398)
			(end 0.508 -0.9398)
			(stroke
				(width 0)
				(type default)
			)
			(fill no)
			(layer "F.CrtYd")
		)
		(fp_rect
			(start -0.508 0.9398)
			(end 0.508 -0.9398)
			(stroke
				(width 0)
				(type default)
			)
			(fill no)
			(layer "F.Fab")
		)
		(pad "1" smd custom
			(at 0 -0.4445)
			(size 0.1397 0.1397)
			(layers "F.Cu" "F.Mask" "F.Paste")
			(net "SW_HDD_G15")
			(options
				(clearance outline)
				(anchor circle)
			)
			(primitives
				(gr_poly
					(pts
						(arc
							(start -0.1778 -0.2794)
							(mid -0.249642 -0.249642)
							(end -0.2794 -0.1778)
						)
						(arc
							(start -0.2794 0.1778)
							(mid -0.249642 0.249642)
							(end -0.1778 0.2794)
						)
						(arc
							(start 0.1778 0.2794)
							(mid 0.249642 0.249642)
							(end 0.2794 0.1778)
						)
						(arc
							(start 0.2794 -0.1778)
							(mid 0.249642 -0.249642)
							(end 0.1778 -0.2794)
						)
					)
					(width 0)
					(fill yes)
				)
			)
		)
		(pad "2" smd custom
			(at 0 0.4445)
			(size 0.1397 0.1397)
			(layers "F.Cu" "F.Mask" "F.Paste")
			(net "SW_HDD_R15")
			(options
				(clearance outline)
				(anchor circle)
			)
			(primitives
				(gr_poly
					(pts
						(arc
							(start -0.1778 -0.2794)
							(mid -0.249642 -0.249642)
							(end -0.2794 -0.1778)
						)
						(arc
							(start -0.2794 0.1778)
							(mid -0.249642 0.249642)
							(end -0.1778 0.2794)
						)
						(arc
							(start 0.1778 0.2794)
							(mid 0.249642 0.249642)
							(end 0.2794 0.1778)
						)
						(arc
							(start 0.2794 -0.1778)
							(mid 0.249642 -0.249642)
							(end 0.1778 -0.2794)
						)
					)
					(width 0)
					(fill yes)
				)
			)
		)
	)
	(footprint ""
		(layer "F.Cu")
		(at 83.784948 -55.285894 180)
		(property "Reference" "Q155"
			(at 0 0 180)
			(layer "F.SilkS")
			(hide yes)
			(effects
				(font
					(size 1.27 1.27)
				)
			)
		)
		(property "Value" "AO4406AL-GP"
			(at -3.707384 -1.5367 180)
			(unlocked yes)
			(layer "F.Fab")
			(hide yes)
			(effects
				(font
					(size 1.016 1.016)
					(thickness 0.1524)
				)
			)
		)
		(property "Device Type" "SOIC8H69"
			(at -3.707384 -3.0607 180)
			(unlocked yes)
			(layer "F.Fab")
			(hide yes)
			(effects
				(font
					(size 1.016 1.016)
					(thickness 0.1524)
				)
			)
		)
		(duplicate_pad_numbers_are_jumpers no)
		(fp_line
			(start 2.1336 1.4224)
			(end 2.1336 -1.4224)
			(stroke
				(width 0.1524)
				(type default)
			)
			(layer "F.SilkS")
		)
		(fp_line
			(start 2.1336 -1.4224)
			(end -2.7432 -1.4224)
			(stroke
				(width 0.1524)
				(type default)
			)
			(layer "F.SilkS")
		)
		(fp_line
			(start -2.1844 -0.0508)
			(end -2.7178 0.508)
			(stroke
				(width 0.1524)
				(type default)
			)
			(layer "F.SilkS")
		)
		(fp_line
			(start -2.6289 3.4417)
			(end -2.6289 1.4732)
			(stroke
				(width 0.381)
				(type default)
			)
			(layer "F.SilkS")
		)
		(fp_line
			(start -2.7178 -0.508)
			(end -2.1844 -0.0508)
			(stroke
				(width 0.1524)
				(type default)
			)
			(layer "F.SilkS")
		)
		(fp_line
			(start -2.7432 1.4224)
			(end 2.1336 1.4224)
			(stroke
				(width 0.1524)
				(type default)
			)
			(layer "F.SilkS")
		)
		(fp_line
			(start -2.7432 1.4224)
			(end -2.6416 1.4224)
			(stroke
				(width 0.1524)
				(type default)
			)
			(layer "F.SilkS")
		)
		(fp_line
			(start -2.7432 -1.4224)
			(end -2.7432 1.4224)
			(stroke
				(width 0.1524)
				(type default)
			)
			(layer "F.SilkS")
		)
		(fp_poly
			(pts
				(xy -2.2098 -1.4224) (xy -2.2098 1.4224) (xy 2.2098 1.4224) (xy 2.2098 -1.4224)
			)
			(stroke
				(width 0)
				(type default)
			)
			(fill yes)
			(layer "F.SilkS")
		)
		(fp_rect
			(start -2.450084 2.999994)
			(end 2.450084 -2.999994)
			(stroke
				(width 0)
				(type default)
			)
			(fill no)
			(layer "F.CrtYd")
		)
		(fp_poly
			(pts
				(xy -2.8194 3.6322) (xy -2.8194 -3.6322) (xy 2.8194 -3.6322) (xy 2.8194 1.18364) (xy 2.450084 1.18364)
				(xy 2.450084 -2.999994) (xy -2.450084 -2.999994) (xy -2.450084 2.999994) (xy 2.450084 2.999994)
				(xy 2.450084 1.18618) (xy 2.8194 1.18618) (xy 2.8194 3.6322)
			)
			(stroke
				(width 0)
				(type default)
			)
			(fill no)
			(layer "F.CrtYd")
		)
		(fp_rect
			(start -2.8194 3.6322)
			(end 2.8194 -3.6322)
			(stroke
				(width 0)
				(type default)
			)
			(fill no)
			(layer "F.Fab")
		)
		(pad "1" smd rect
			(at -1.905 2.54 180)
			(size 0.635 1.651)
			(layers "F.Cu" "F.Mask" "F.Paste")
			(net "P5V_HDD26")
		)
		(pad "2" smd rect
			(at -0.635 2.54 180)
			(size 0.635 1.651)
			(layers "F.Cu" "F.Mask" "F.Paste")
			(net "P5V_HDD26")
		)
		(pad "3" smd rect
			(at 0.635 2.54 180)
			(size 0.635 1.651)
			(layers "F.Cu" "F.Mask" "F.Paste")
			(net "P5V_HDD26")
		)
		(pad "4" smd rect
			(at 1.905 2.54 180)
			(size 0.635 1.651)
			(layers "F.Cu" "F.Mask" "F.Paste")
			(net "SW_HDD_P26")
		)
		(pad "5" smd rect
			(at 1.905 -2.54 180)
			(size 0.635 1.651)
			(layers "F.Cu" "F.Mask" "F.Paste")
			(net "P5V_A_2")
		)
		(pad "6" smd rect
			(at 0.635 -2.54 180)
			(size 0.635 1.651)
			(layers "F.Cu" "F.Mask" "F.Paste")
			(net "P5V_A_2")
		)
		(pad "7" smd rect
			(at -0.635 -2.54 180)
			(size 0.635 1.651)
			(layers "F.Cu" "F.Mask" "F.Paste")
			(net "P5V_A_2")
		)
		(pad "8" smd rect
			(at -1.905 -2.54 180)
			(size 0.635 1.651)
			(layers "F.Cu" "F.Mask" "F.Paste")
			(net "P5V_A_2")
		)
	)
)
